(kicad_pcb
	(version 20241229)
	(generator "pcbnew")
	(generator_version "9.0")
	(general
		(thickness 1.61)
		(legacy_teardrops no)
	)
	(paper "A3")
	(title_block
		(title "RDIMM DDR5 Tester")
		(date "2026-05-21")
		(rev "2.2.0")
		(company "Antmicro")
		(comment 9 "footprints 155-156 of 796")
	)
	(layers
		(0 "F.Cu" signal)
		(4 "In1.Cu" power)
		(6 "In2.Cu" mixed)
		(8 "In3.Cu" power)
		(10 "In4.Cu" mixed)
		(12 "In5.Cu" power)
		(14 "In6.Cu" mixed)
		(16 "In7.Cu" power)
		(18 "In8.Cu" power)
		(20 "In9.Cu" mixed)
		(22 "In10.Cu" power)
		(2 "B.Cu" signal)
		(9 "F.Adhes" user "F.Adhesive")
		(11 "B.Adhes" user "B.Adhesive")
		(13 "F.Paste" user)
		(15 "B.Paste" user)
		(5 "F.SilkS" user "F.Silkscreen")
		(7 "B.SilkS" user "B.Silkscreen")
		(1 "F.Mask" user)
		(3 "B.Mask" user)
		(17 "Dwgs.User" user "User.Drawings")
		(19 "Cmts.User" user "User.Comments")
		(21 "Eco1.User" user "User.Eco1")
		(23 "Eco2.User" user "User.Eco2")
		(25 "Edge.Cuts" user)
		(27 "Margin" user)
		(31 "F.CrtYd" user "F.Courtyard")
		(29 "B.CrtYd" user "B.Courtyard")
		(35 "F.Fab" user)
		(33 "B.Fab" user)
	)
	(footprint "antmicro-footprints:LGA-33_7x7mm_P0.65mm"
		(layer "F.Cu")
		(at 255.645 172.7595 -90)
		(property "Reference" "U19"
			(at 5.0405 4.795 0)
			(layer "F.SilkS")
			(effects
				(font
					(size 0.7 0.7)
					(thickness 0.15)
				)
				(justify left bottom)
			)
		)
		(property "Value" "MPM54304GMN"
			(at 0 5 90)
			(layer "F.Fab")
			(effects
				(font
					(size 0.7 0.7)
					(thickness 0.15)
				)
				(justify right bottom)
			)
		)
		(property "Datasheet" "https://www.monolithicpower.com/en/documentview/productdocument/index/version/2/document_type/Datasheet/lang/en/sku/MPM54304/document_id/4982/"
			(at 0 0 270)
			(layer "F.Fab")
			(hide yes)
			(effects
				(font
					(size 1.27 1.27)
					(thickness 0.15)
				)
			)
		)
		(property "MPN" "MPM54304GMN-0000"
			(at 0 0 270)
			(unlocked yes)
			(layer "F.Fab")
			(hide yes)
			(effects
				(font
					(size 1 1)
					(thickness 0.15)
				)
			)
		)
		(property "Manufacturer" "Monolithic Power Systems"
			(at 0 0 270)
			(unlocked yes)
			(layer "F.Fab")
			(hide yes)
			(effects
				(font
					(size 1 1)
					(thickness 0.15)
				)
			)
		)
		(property "Author" "Antmicro"
			(at 0 0 270)
			(unlocked yes)
			(layer "F.Fab")
			(hide yes)
			(effects
				(font
					(size 1 1)
					(thickness 0.15)
				)
			)
		)
		(property "License" "Apache-2.0"
			(at 0 0 270)
			(unlocked yes)
			(layer "F.Fab")
			(hide yes)
			(effects
				(font
					(size 1 1)
					(thickness 0.15)
				)
			)
		)
		(property ki_fp_filters "CP_48_13_ADI CP_48_13_ADI-M CP_48_13_ADI-L")
		(sheetname "/Supply/DC-DC AUX, MGT/")
		(sheetfile "dc-dc-aux-mgt.kicad_sch")
		(solder_paste_margin_ratio -0.1)
		(attr smd)
		(fp_line
			(start -3.65 3.648)
			(end -3.65 2.922)
			(stroke
				(width 0.15)
				(type solid)
			)
			(layer "F.SilkS")
		)
		(fp_line
			(start -2.926 3.648)
			(end -3.65 3.648)
			(stroke
				(width 0.15)
				(type solid)
			)
			(layer "F.SilkS")
		)
		(fp_line
			(start 2.922 3.648)
			(end 3.648 3.648)
			(stroke
				(width 0.15)
				(type solid)
			)
			(layer "F.SilkS")
		)
		(fp_line
			(start 3.648 3.648)
			(end 3.648 2.922)
			(stroke
				(width 0.15)
				(type solid)
			)
			(layer "F.SilkS")
		)
		(fp_line
			(start -3.665 -2.928)
			(end -3.665 -3.653)
			(stroke
				(width 0.15)
				(type solid)
			)
			(layer "F.SilkS")
		)
		(fp_line
			(start 2.922 -3.65)
			(end 3.648 -3.65)
			(stroke
				(width 0.15)
				(type solid)
			)
			(layer "F.SilkS")
		)
		(fp_line
			(start 3.648 -3.65)
			(end 3.648 -2.926)
			(stroke
				(width 0.15)
				(type solid)
			)
			(layer "F.SilkS")
		)
		(fp_line
			(start -3.665 -3.653)
			(end -2.94 -3.653)
			(stroke
				(width 0.15)
				(type solid)
			)
			(layer "F.SilkS")
		)
		(fp_circle
			(center -3.8 -1.925)
			(end -3.75 -1.925)
			(stroke
				(width 0.15)
				(type solid)
			)
			(fill yes)
			(layer "F.SilkS")
		)
		(fp_rect
			(start -4 -4)
			(end 3.999 3.999)
			(stroke
				(width 0.05)
				(type solid)
			)
			(fill no)
			(layer "F.CrtYd")
		)
		(fp_line
			(start -3.5 3.499)
			(end 3.499 3.499)
			(stroke
				(width 0.15)
				(type solid)
			)
			(layer "F.Fab")
		)
		(fp_line
			(start 3.499 3.499)
			(end 3.499 -3.5)
			(stroke
				(width 0.15)
				(type solid)
			)
			(layer "F.Fab")
		)
		(fp_line
			(start -3.5 -3.5)
			(end -3.5 3.499)
			(stroke
				(width 0.15)
				(type solid)
			)
			(layer "F.Fab")
		)
		(fp_line
			(start -3.101 -3.5)
			(end -3.5 -3.101)
			(stroke
				(width 0.15)
				(type solid)
			)
			(layer "F.Fab")
		)
		(fp_line
			(start 3.499 -3.5)
			(end -3.5 -3.5)
			(stroke
				(width 0.15)
				(type solid)
			)
			(layer "F.Fab")
		)
		(fp_text user "License: Apache-2.0"
			(at -4.35 9.699 270)
			(layer "F.Fab")
			(effects
				(font
					(size 0.7 0.7)
					(thickness 0.15)
				)
				(justify left bottom)
			)
		)
		(fp_text user "Author: Antmicro"
			(at -4.35 7.299 270)
			(layer "F.Fab")
			(effects
				(font
					(size 0.7 0.7)
					(thickness 0.15)
				)
				(justify left bottom)
			)
		)
		(fp_text user "${REFERENCE}"
			(at -4.35 8.499 270)
			(layer "F.Fab")
			(effects
				(font
					(size 0.7 0.7)
					(thickness 0.15)
				)
				(justify left bottom)
			)
		)
		(pad "1" smd rect
			(at -3.138 -1.625)
			(size 0.3 1.125)
			(layers "F.Cu" "F.Mask" "F.Paste")
			(net 47 "/Supply/DC-DC AUX, MGT/MGTAVCC_local")
			(pinfunction "VOUT3")
			(pintype "power_out")
		)
		(pad "2" smd rect
			(at -3.138 -0.975)
			(size 0.3 1.125)
			(layers "F.Cu" "F.Mask" "F.Paste")
			(net 1 "GND")
			(pinfunction "GND")
			(pintype "passive")
		)
		(pad "3" smd rect
			(at -3.138 -0.328)
			(size 0.3 1.125)
			(layers "F.Cu" "F.Mask" "F.Paste")
			(net 533 "/I^{2}C + I3C/PWR.SDA")
			(pinfunction "SDA")
			(pintype "bidirectional")
		)
		(pad "4" smd rect
			(at -3.138 0.325)
			(size 0.3 1.125)
			(layers "F.Cu" "F.Mask" "F.Paste")
			(net 749 "/I^{2}C + I3C/PWR.SCL")
			(pinfunction "SCL")
			(pintype "input")
		)
		(pad "5" smd rect
			(at -3.138 0.972)
			(size 0.3 1.125)
			(layers "F.Cu" "F.Mask" "F.Paste")
			(net 1 "GND")
			(pinfunction "GND")
			(pintype "passive")
		)
		(pad "6" smd rect
			(at -3.138 1.624)
			(size 0.3 1.125)
			(layers "F.Cu" "F.Mask" "F.Paste")
			(net 713 "/Supply/DC-DC AUX, MGT/FB2")
			(pinfunction "FB2")
			(pintype "input")
		)
		(pad "7" smd rect
			(at -2.926 3.136 90)
			(size 0.3 1.125)
			(layers "F.Cu" "F.Mask" "F.Paste")
			(net 1 "GND")
			(pinfunction "GND")
			(pintype "passive")
		)
		(pad "8" smd rect
			(at -2.275 3.136 90)
			(size 0.3 1.125)
			(layers "F.Cu" "F.Mask" "F.Paste")
			(net 48 "/Supply/DC-DC AUX, MGT/MGTAVTT_local")
			(pinfunction "VOUT2")
			(pintype "power_out")
		)
		(pad "9" smd rect
			(at -1.625 3.136 270)
			(size 0.3 1.125)
			(layers "F.Cu" "F.Mask" "F.Paste")
			(net 48 "/Supply/DC-DC AUX, MGT/MGTAVTT_local")
			(pinfunction "VOUT2")
			(pintype "passive")
		)
		(pad "10" smd rect
			(at -0.975 3.136 270)
			(size 0.3 1.125)
			(layers "F.Cu" "F.Mask" "F.Paste")
			(net 1 "GND")
			(pinfunction "GND")
			(pintype "passive")
		)
		(pad "11" smd rect
			(at -0.328 3.136 270)
			(size 0.3 1.125)
			(layers "F.Cu" "F.Mask" "F.Paste")
			(net 430 "unconnected-(U19-SW2-Pad11)")
			(pinfunction "SW2")
			(pintype "power_out+no_connect")
		)
		(pad "12" smd rect
			(at 0.325 3.136 270)
			(size 0.3 1.125)
			(layers "F.Cu" "F.Mask" "F.Paste")
			(net 431 "unconnected-(U19-SW1-Pad12)")
			(pinfunction "SW1")
			(pintype "power_out+no_connect")
		)
		(pad "13" smd rect
			(at 0.972 3.136 270)
			(size 0.3 1.125)
			(layers "F.Cu" "F.Mask" "F.Paste")
			(net 1 "GND")
			(pinfunction "GND")
			(pintype "passive")
		)
		(pad "14" smd rect
			(at 1.624 3.136 270)
			(size 0.3 1.125)
			(layers "F.Cu" "F.Mask" "F.Paste")
			(net 37 "/Supply/DC-DC AUX, MGT/1V8_local")
			(pinfunction "VOUT1")
			(pintype "power_out")
		)
		(pad "15" smd rect
			(at 2.273 3.136 270)
			(size 0.3 1.125)
			(layers "F.Cu" "F.Mask" "F.Paste")
			(net 37 "/Supply/DC-DC AUX, MGT/1V8_local")
			(pinfunction "VOUT1")
			(pintype "passive")
		)
		(pad "16" smd rect
			(at 2.922 3.136 270)
			(size 0.3 1.125)
			(layers "F.Cu" "F.Mask" "F.Paste")
			(net 1 "GND")
			(pinfunction "GND")
			(pintype "passive")
		)
		(pad "17" smd rect
			(at 3.136 1.624)
			(size 0.3 1.125)
			(layers "F.Cu" "F.Mask" "F.Paste")
			(net 1 "GND")
			(pinfunction "SGND1")
			(pintype "power_out")
		)
		(pad "18" smd rect
			(at 3.136 0.972)
			(size 0.3 1.125)
			(layers "F.Cu" "F.Mask" "F.Paste")
			(net 712 "/Supply/DC-DC AUX, MGT/FB1")
			(pinfunction "FB1")
			(pintype "input")
		)
		(pad "19" smd rect
			(at 3.136 0.325)
			(size 0.3 1.125)
			(layers "F.Cu" "F.Mask" "F.Paste")
			(net 169 "/Supply/EN2")
			(pinfunction "EN/SYNCI")
			(pintype "input")
		)
		(pad "20" smd rect
			(at 3.136 -0.328)
			(size 0.3 1.125)
			(layers "F.Cu" "F.Mask" "F.Paste")
			(net 1 "GND")
			(pinfunction "GND")
			(pintype "passive")
		)
		(pad "21" smd rect
			(at 3.136 -0.975)
			(size 0.3 1.125)
			(layers "F.Cu" "F.Mask" "F.Paste")
			(net 1 "GND")
			(pinfunction "GND")
			(pintype "passive")
		)
		(pad "22" smd rect
			(at 3.136 -1.625)
			(size 0.3 1.125)
			(layers "F.Cu" "F.Mask" "F.Paste")
			(net 225 "/Supply/DC-DC AUX, MGT/MGTAVCCAUX_local")
			(pinfunction "VOUT4")
			(pintype "power_out")
		)
		(pad "23" smd rect
			(at 2.922 -3.138 90)
			(size 0.3 1.125)
			(layers "F.Cu" "F.Mask" "F.Paste")
			(net 225 "/Supply/DC-DC AUX, MGT/MGTAVCCAUX_local")
			(pinfunction "VOUT4")
			(pintype "passive")
		)
		(pad "24" smd rect
			(at 2.273 -3.138 90)
			(size 0.3 1.125)
			(layers "F.Cu" "F.Mask" "F.Paste")
			(net 717 "/Supply/DC-DC AUX, MGT/FB4")
			(pinfunction "FB4")
			(pintype "input")
		)
		(pad "25" smd rect
			(at 1.624 -3.138 270)
			(size 0.3 1.125)
			(layers "F.Cu" "F.Mask" "F.Paste")
			(net 9 "/Supply/DC-DC AUX, MGT/QDCDC1_VCC")
			(pinfunction "VCC")
			(pintype "input")
		)
		(pad "26" smd rect
			(at 0.972 -3.138 270)
			(size 0.3 1.125)
			(layers "F.Cu" "F.Mask" "F.Paste")
			(net 484 "PG2")
			(pinfunction "GPIO")
			(pintype "input")
		)
		(pad "27" smd rect
			(at 0.325 -3.138 270)
			(size 0.3 1.125)
			(layers "F.Cu" "F.Mask" "F.Paste")
			(net 1 "GND")
			(pinfunction "GND")
			(pintype "passive")
		)
		(pad "28" smd rect
			(at -0.328 -3.138 270)
			(size 0.3 1.125)
			(layers "F.Cu" "F.Mask" "F.Paste")
			(net 35 "VDC")
			(pinfunction "VIN")
			(pintype "input")
		)
		(pad "29" smd rect
			(at -0.975 -3.138 270)
			(size 0.3 1.125)
			(layers "F.Cu" "F.Mask" "F.Paste")
			(net 35 "VDC")
			(pinfunction "VIN")
			(pintype "passive")
		)
		(pad "30" smd rect
			(at -1.625 -3.138 270)
			(size 0.3 1.125)
			(layers "F.Cu" "F.Mask" "F.Paste")
			(net 1 "GND")
			(pinfunction "SGND2")
			(pintype "power_out")
		)
		(pad "31" smd rect
			(at -2.275 -3.138 270)
			(size 0.3 1.125)
			(layers "F.Cu" "F.Mask" "F.Paste")
			(net 716 "/Supply/DC-DC AUX, MGT/FB3")
			(pinfunction "FB3")
			(pintype "input")
		)
		(pad "32" smd rect
			(at -2.926 -3.138 270)
			(size 0.3 1.125)
			(layers "F.Cu" "F.Mask" "F.Paste")
			(net 47 "/Supply/DC-DC AUX, MGT/MGTAVCC_local")
			(pinfunction "VOUT3")
			(pintype "passive")
		)
		(pad "33" smd rect
			(at -0.863 -0.863 270)
			(size 1.725 1.725)
			(layers "F.Cu" "F.Mask" "F.Paste")
			(net 1 "GND")
			(pinfunction "GND")
			(pintype "passive")
			(solder_paste_margin -0.1)
		)
		(pad "33" smd rect
			(at -0.863 0.86 270)
			(size 1.725 1.725)
			(layers "F.Cu" "F.Mask" "F.Paste")
			(net 1 "GND")
			(pinfunction "GND")
			(pintype "passive")
			(solder_paste_margin -0.1)
		)
		(pad "33" smd rect
			(at 0.86 -0.863 270)
			(size 1.725 1.725)
			(layers "F.Cu" "F.Mask" "F.Paste")
			(net 1 "GND")
			(pinfunction "GND")
			(pintype "passive")
			(solder_paste_margin -0.1)
		)
		(pad "33" smd rect
			(at 0.86 0.86 270)
			(size 1.725 1.725)
			(layers "F.Cu" "F.Mask" "F.Paste")
			(net 1 "GND")
			(pinfunction "GND")
			(pintype "passive")
			(solder_paste_margin -0.1)
		)
	)
	(footprint "antmicro-footprints:R_0402_1005Metric"
		(layer "F.Cu")
		(at 117.088 112.722921 -90)
		(descr "Resistor SMD 0402")
		(tags "resistor SMD 0402")
		(property "Reference" "R19"
			(at -1.072921 0.563 90)
			(layer "F.SilkS")
			(effects
				(font
					(size 0.7 0.7)
					(thickness 0.15)
				)
				(justify right bottom)
			)
		)
		(property "Value" "R_330R_0402"
			(at -1.011843 1.772047 90)
			(layer "F.Fab")
			(effects
				(font
					(size 0.7 0.7)
					(thickness 0.15)
				)
				(justify right bottom)
			)
		)
		(property "Datasheet" "https://www.bourns.com/docs/product-datasheets/cr.pdf"
			(at 0 0 270)
			(layer "F.Fab")
			(hide yes)
			(effects
				(font
					(size 1.27 1.27)
					(thickness 0.15)
				)
			)
		)
		(property "Manufacturer" "Bourns"
			(at 0 0 270)
			(unlocked yes)
			(layer "F.Fab")
			(hide yes)
			(effects
				(font
					(size 1 1)
					(thickness 0.15)
				)
			)
		)
		(property "MPN" "CR0402-FX-3300GLF"
			(at 0 0 270)
			(unlocked yes)
			(layer "F.Fab")
			(hide yes)
			(effects
				(font
					(size 1 1)
					(thickness 0.15)
				)
			)
		)
		(property "Val" "330R"
			(at 0 0 270)
			(unlocked yes)
			(layer "F.Fab")
			(hide yes)
			(effects
				(font
					(size 1 1)
					(thickness 0.15)
				)
			)
		)
		(property "License" "Apache-2.0"
			(at 0 0 270)
			(unlocked yes)
			(layer "F.Fab")
			(hide yes)
			(effects
				(font
					(size 1 1)
					(thickness 0.15)
				)
			)
		)
		(property "Author" "Antmicro"
			(at 0 0 270)
			(unlocked yes)
			(layer "F.Fab")
			(hide yes)
			(effects
				(font
					(size 1 1)
					(thickness 0.15)
				)
			)
		)
		(property "Tolerance" "1%"
			(at 0 0 270)
			(unlocked yes)
			(layer "F.Fab")
			(hide yes)
			(effects
				(font
					(size 1 1)
					(thickness 0.15)
				)
			)
		)
		(sheetname "/FPGA Config/")
		(sheetfile "fpga-config.kicad_sch")
		(attr smd)
		(fp_rect
			(start -0.925 -0.47)
			(end 0.925 0.47)
			(stroke
				(width 0.05)
				(type default)
			)
			(fill no)
			(layer "F.CrtYd")
		)
		(fp_rect
			(start -0.5 -0.25)
			(end 0.5 0.25)
			(stroke
				(width 0.15)
				(type solid)
			)
			(fill no)
			(layer "F.Fab")
		)
		(fp_text user "Author: Antmicro"
			(at -0.95 4.169 270)
			(layer "F.Fab")
			(effects
				(font
					(size 0.7 0.7)
					(thickness 0.15)
				)
				(justify left bottom)
			)
		)
		(fp_text user "License: Apache-2.0"
			(at -0.95 5.169 270)
			(layer "F.Fab")
			(effects
				(font
					(size 0.7 0.7)
					(thickness 0.15)
				)
				(justify left bottom)
			)
		)
		(fp_text user "${REFERENCE}"
			(at -0.95 3.168 270)
			(layer "F.Fab")
			(effects
				(font
					(size 0.7 0.7)
					(thickness 0.15)
				)
				(justify left bottom)
			)
		)
		(pad "1" smd roundrect
			(at -0.48 0 270)
			(size 0.59 0.64)
			(layers "F.Cu" "F.Mask" "F.Paste")
			(roundrect_rratio 0.25)
			(net 797 "+1V8")
			(pintype "passive")
		)
		(pad "2" smd roundrect
			(at 0.48 0 270)
			(size 0.59 0.64)
			(layers "F.Cu" "F.Mask" "F.Paste")
			(roundrect_rratio 0.25)
			(net 340 "/FPGA Config/DONE")
			(pintype "passive")
		)
	)
)
